FILE_TYPE = MULTI_PHYS_TABLE;

PART 'TPS3808G18DBVR_SOT23_6'
CLASS = IC 

{========================================================================================}
:CLS_PN             = JEDEC_TYPE                       |ALT_SYMBOLS                          |DESCRIPTION                                                                           ;
{========================================================================================}
'G222-10157-01'      = 'SOT23_6'  |'(SOT23_6)'  |'IC,TPS3808G18,PWR-SPVR,ADJ,SOT23-6'  
'G222-00082-01'      = 'SOT23_6'  |'(SOT23_6)'  |'IC,TPS3808G33,PWR-SUPRVSR,ADJ,SOT23-6' 
'G222-00042-01'     = 'SOT23_6'  | '(SOT23_6)' | 'IC,TPS3808G01,PWR-SPVR,ADJ,SOT23-6'

END_PART

END.

